(kicad_pcb
	(version 20260206)
	(generator "pcbnew")
	(generator_version "10.0")
	(general
		(thickness 1.6)
		(legacy_teardrops no)
	)
	(paper "A4")
	(title_block
		(title "panther-plus-userver — 13130-1b_20150205.brd")
		(comment 1 "Honey Badger (Wiwynn) / footprint 1214 of 1509 (DIMM3), pads 79-85 of 210")
	)
	(layers
		(0 "F.Cu" signal "TOP")
		(4 "In1.Cu" signal "L2")
		(6 "In2.Cu" signal "L3")
		(8 "In3.Cu" signal "L4")
		(10 "In4.Cu" signal "L5")
		(12 "In5.Cu" signal "L6")
		(14 "In6.Cu" signal "L7")
		(16 "In7.Cu" signal "L8")
		(18 "In8.Cu" signal "L9")
		(20 "In9.Cu" signal "L10")
		(22 "In10.Cu" signal "L11")
		(2 "B.Cu" signal "BOTTOM")
		(9 "F.Adhes" user "F.Adhesive")
		(11 "B.Adhes" user "B.Adhesive")
		(13 "F.Paste" user "Package Geometry/Pastemask Top")
		(15 "B.Paste" user "Package Geometry/Pastemask Bottom")
		(5 "F.SilkS" user "Ref Des/Silkscreen Top")
		(7 "B.SilkS" user "Ref Des/Silkscreen Bottom")
		(1 "F.Mask" user "Board Geometry/Soldermask Top")
		(3 "B.Mask" user "Board Geometry/Soldermask Bottom")
		(17 "Dwgs.User" user "User.Drawings")
		(19 "Cmts.User" user "User.Comments")
		(21 "Eco1.User" user "User.Eco1")
		(23 "Eco2.User" user "User.Eco2")
		(25 "Edge.Cuts" user "Board Geometry/Outline")
		(27 "Margin" user)
		(31 "F.CrtYd" user "Package Geometry/Place Bound Top")
		(29 "B.CrtYd" user "Package Geometry/Place Bound Bottom")
		(35 "F.Fab" user "Ref Des/Assembly Top")
		(33 "B.Fab" user "Ref Des/Assembly Bottom")
	)
	(footprint ""
		(layer "B.Cu")
		(at 159.999934 -5.790692)
		(property "Reference" "DIMM3"
			(at 0 0 0)
			(layer "B.SilkS")
			(hide yes)
			(effects
				(font
					(size 1.27 1.27)
				)
				(justify mirror)
			)
		)
		(property "Value" "DDR3-204P-142-COLAY-1-GP-U"
			(at 41.312338 -16.676878 0)
			(unlocked yes)
			(layer "B.Fab")
			(hide yes)
			(effects
				(font
					(size 1.016 1.016)
					(thickness 0.1524)
				)
				(justify mirror)
			)
		)
		(property "Device Type" "AS0A626-J8R6-7H-COLAY-1"
			(at 41.312338 -18.200878 0)
			(unlocked yes)
			(layer "B.Fab")
			(hide yes)
			(effects
				(font
					(size 1.016 1.016)
					(thickness 0.1524)
				)
				(justify mirror)
			)
		)
		(duplicate_pad_numbers_are_jumpers no)
		(pad "77" smd custom
			(at -6.450076 -4.100068 180)
			(size 0.1143 0.1143)
			(layers "B.Cu" "B.Mask" "B.Paste")
			(net "M_B_DQS_DP8")
			(options
				(clearance outline)
				(anchor circle)
			)
			(primitives
				(gr_poly
					(pts
						(xy 0 -0.9017) (xy -0.03175 -0.89916) (xy -0.0635 -0.889) (xy -0.09144 -0.87376) (xy -0.11684 -0.85344)
						(xy -0.13716 -0.82804) (xy -0.1524 -0.8001) (xy -0.16256 -0.76835) (xy -0.1651 -0.7366) (xy -0.1651 -0.44958)
						(xy -0.17272 -0.44196) (xy -0.19812 -0.4064) (xy -0.2032 -0.39624) (xy -0.20701 -0.38735) (xy -0.21209 -0.37719)
						(xy -0.2159 -0.36703) (xy -0.21844 -0.35687) (xy -0.22225 -0.34544) (xy -0.22352 -0.33528) (xy -0.22606 -0.32512)
						(xy -0.22733 -0.31369) (xy -0.22733 -0.30353) (xy -0.2286 -0.2921) (xy -0.22733 -0.28067) (xy -0.22733 -0.27051)
						(xy -0.22606 -0.25908) (xy -0.22352 -0.24892) (xy -0.22225 -0.23876) (xy -0.21844 -0.22733) (xy -0.2159 -0.21717)
						(xy -0.21209 -0.20701) (xy -0.20701 -0.19685) (xy -0.2032 -0.18796) (xy -0.19812 -0.1778) (xy -0.17272 -0.14224)
						(xy -0.1651 -0.13462) (xy -0.1651 0.7366) (xy -0.16256 0.76835) (xy -0.1524 0.8001) (xy -0.13716 0.82804)
						(xy -0.11684 0.85344) (xy -0.09144 0.87376) (xy -0.0635 0.889) (xy -0.03175 0.89916) (xy 0 0.9017)
						(xy 0.03175 0.89916) (xy 0.0635 0.889) (xy 0.09144 0.87376) (xy 0.11684 0.85344) (xy 0.13716 0.82804)
						(xy 0.1524 0.8001) (xy 0.16256 0.76835) (xy 0.1651 0.7366) (xy 0.1651 -0.13462) (xy 0.17272 -0.14224)
						(xy 0.19812 -0.1778) (xy 0.2032 -0.18796) (xy 0.20701 -0.19685) (xy 0.21209 -0.20701) (xy 0.2159 -0.21717)
						(xy 0.21844 -0.22733) (xy 0.22225 -0.23876) (xy 0.22352 -0.24892) (xy 0.22606 -0.25908) (xy 0.22733 -0.27051)
						(xy 0.22733 -0.28067) (xy 0.2286 -0.2921) (xy 0.22733 -0.30353) (xy 0.22733 -0.31369) (xy 0.22606 -0.32512)
						(xy 0.22352 -0.33528) (xy 0.22225 -0.34544) (xy 0.21844 -0.35687) (xy 0.2159 -0.36703) (xy 0.21209 -0.37719)
						(xy 0.20701 -0.38735) (xy 0.2032 -0.39624) (xy 0.19812 -0.4064) (xy 0.17272 -0.44196) (xy 0.1651 -0.44958)
						(xy 0.1651 -0.7366) (xy 0.16256 -0.76835) (xy 0.1524 -0.8001) (xy 0.13716 -0.82804) (xy 0.11684 -0.85344)
						(xy 0.09144 -0.87376) (xy 0.0635 -0.889) (xy 0.03175 -0.89916)
					)
					(width 0)
					(fill yes)
				)
			)
		)
		(pad "78" smd custom
			(at -6.150102 4.100068 180)
			(size 0.1143 0.1143)
			(layers "B.Cu" "B.Mask" "B.Paste")
			(net "GND")
			(options
				(clearance outline)
				(anchor circle)
			)
			(primitives
				(gr_poly
					(pts
						(xy 0 -0.9017) (xy -0.03175 -0.89916) (xy -0.0635 -0.889) (xy -0.09144 -0.87376) (xy -0.11684 -0.85344)
						(xy -0.13716 -0.82804) (xy -0.1524 -0.8001) (xy -0.16256 -0.76835) (xy -0.1651 -0.7366) (xy -0.1651 0.13462)
						(xy -0.17272 0.14224) (xy -0.19812 0.1778) (xy -0.2032 0.18796) (xy -0.20701 0.19685) (xy -0.21209 0.20701)
						(xy -0.2159 0.21717) (xy -0.21844 0.22733) (xy -0.22225 0.23876) (xy -0.22352 0.24892) (xy -0.22606 0.25908)
						(xy -0.22733 0.27051) (xy -0.22733 0.28067) (xy -0.2286 0.2921) (xy -0.22733 0.30353) (xy -0.22733 0.31369)
						(xy -0.22606 0.32512) (xy -0.22352 0.33528) (xy -0.22225 0.34544) (xy -0.21844 0.35687) (xy -0.2159 0.36703)
						(xy -0.21209 0.37719) (xy -0.20701 0.38735) (xy -0.2032 0.39624) (xy -0.19812 0.4064) (xy -0.17272 0.44196)
						(xy -0.1651 0.44958) (xy -0.1651 0.7366) (xy -0.16256 0.76835) (xy -0.1524 0.8001) (xy -0.13716 0.82804)
						(xy -0.11684 0.85344) (xy -0.09144 0.87376) (xy -0.0635 0.889) (xy -0.03175 0.89916) (xy 0 0.9017)
						(xy 0.03175 0.89916) (xy 0.0635 0.889) (xy 0.09144 0.87376) (xy 0.11684 0.85344) (xy 0.13716 0.82804)
						(xy 0.1524 0.8001) (xy 0.16256 0.76835) (xy 0.1651 0.7366) (xy 0.1651 0.44958) (xy 0.17272 0.44196)
						(xy 0.19812 0.4064) (xy 0.2032 0.39624) (xy 0.20701 0.38735) (xy 0.21209 0.37719) (xy 0.2159 0.36703)
						(xy 0.21844 0.35687) (xy 0.22225 0.34544) (xy 0.22352 0.33528) (xy 0.22606 0.32512) (xy 0.22733 0.31369)
						(xy 0.22733 0.30353) (xy 0.2286 0.2921) (xy 0.22733 0.28067) (xy 0.22733 0.27051) (xy 0.22606 0.25908)
						(xy 0.22352 0.24892) (xy 0.22225 0.23876) (xy 0.21844 0.22733) (xy 0.2159 0.21717) (xy 0.21209 0.20701)
						(xy 0.20701 0.19685) (xy 0.2032 0.18796) (xy 0.19812 0.1778) (xy 0.17272 0.14224) (xy 0.1651 0.13462)
						(xy 0.1651 -0.7366) (xy 0.16256 -0.76835) (xy 0.1524 -0.8001) (xy 0.13716 -0.82804) (xy 0.11684 -0.85344)
						(xy 0.09144 -0.87376) (xy 0.0635 -0.889) (xy 0.03175 -0.89916)
					)
					(width 0)
					(fill yes)
				)
			)
		)
		(pad "79" smd custom
			(at -5.849874 -4.100068 180)
			(size 0.1143 0.1143)
			(layers "B.Cu" "B.Mask" "B.Paste")
			(net "GND")
			(options
				(clearance outline)
				(anchor circle)
			)
			(primitives
				(gr_poly
					(pts
						(xy 0 -0.9017) (xy -0.03175 -0.89916) (xy -0.0635 -0.889) (xy -0.09144 -0.87376) (xy -0.11684 -0.85344)
						(xy -0.13716 -0.82804) (xy -0.1524 -0.8001) (xy -0.16256 -0.76835) (xy -0.1651 -0.7366) (xy -0.1651 -0.19685)
						(xy -0.17272 -0.18923) (xy -0.17907 -0.18034) (xy -0.18669 -0.17145) (xy -0.19177 -0.16256) (xy -0.19812 -0.15367)
						(xy -0.20828 -0.13335) (xy -0.21971 -0.10287) (xy -0.22225 -0.09271) (xy -0.22479 -0.08128) (xy -0.22606 -0.07112)
						(xy -0.2286 -0.05969) (xy -0.2286 -0.01651) (xy -0.22606 -0.00508) (xy -0.22479 0.00508) (xy -0.22225 0.01651)
						(xy -0.21971 0.02667) (xy -0.20828 0.05715) (xy -0.19812 0.07747) (xy -0.19177 0.08636) (xy -0.18669 0.09525)
						(xy -0.17907 0.10414) (xy -0.17272 0.11303) (xy -0.1651 0.12065) (xy -0.1651 0.7366) (xy -0.16256 0.76835)
						(xy -0.1524 0.8001) (xy -0.13716 0.82804) (xy -0.11684 0.85344) (xy -0.09144 0.87376) (xy -0.0635 0.889)
						(xy -0.03175 0.89916) (xy 0 0.9017) (xy 0.03175 0.89916) (xy 0.0635 0.889) (xy 0.09144 0.87376)
						(xy 0.11684 0.85344) (xy 0.13716 0.82804) (xy 0.1524 0.8001) (xy 0.16256 0.76835) (xy 0.1651 0.7366)
						(xy 0.1651 0.11938) (xy 0.17272 0.11176) (xy 0.19812 0.0762) (xy 0.2032 0.06604) (xy 0.20701 0.05715)
						(xy 0.21209 0.04699) (xy 0.2159 0.03683) (xy 0.21844 0.02667) (xy 0.22225 0.01524) (xy 0.22352 0.00508)
						(xy 0.22606 -0.00508) (xy 0.22733 -0.01651) (xy 0.22733 -0.02667) (xy 0.2286 -0.0381) (xy 0.22733 -0.04953)
						(xy 0.22733 -0.05969) (xy 0.22606 -0.07112) (xy 0.22352 -0.08128) (xy 0.22225 -0.09144) (xy 0.21844 -0.10287)
						(xy 0.2159 -0.11303) (xy 0.21209 -0.12319) (xy 0.20701 -0.13335) (xy 0.2032 -0.14224) (xy 0.19812 -0.1524)
						(xy 0.17272 -0.18796) (xy 0.1651 -0.19558) (xy 0.1651 -0.7366) (xy 0.16256 -0.76835) (xy 0.1524 -0.8001)
						(xy 0.13716 -0.82804) (xy 0.11684 -0.85344) (xy 0.09144 -0.87376) (xy 0.0635 -0.889) (xy 0.03175 -0.89916)
					)
					(width 0)
					(fill yes)
				)
			)
		)
		(pad "80" smd custom
			(at -5.5499 4.100068 180)
			(size 0.1143 0.1143)
			(layers "B.Cu" "B.Mask" "B.Paste")
			(net "M_B_ECC6")
			(options
				(clearance outline)
				(anchor circle)
			)
			(primitives
				(gr_poly
					(pts
						(xy 0 -0.9017) (xy -0.03175 -0.89916) (xy -0.0635 -0.889) (xy -0.09144 -0.87376) (xy -0.11684 -0.85344)
						(xy -0.13716 -0.82804) (xy -0.1524 -0.8001) (xy -0.16256 -0.76835) (xy -0.1651 -0.7366) (xy -0.1651 -0.11938)
						(xy -0.17272 -0.11176) (xy -0.19812 -0.0762) (xy -0.2032 -0.06604) (xy -0.20701 -0.05715) (xy -0.21209 -0.04699)
						(xy -0.2159 -0.03683) (xy -0.21844 -0.02667) (xy -0.22225 -0.01524) (xy -0.22352 -0.00508) (xy -0.22606 0.00508)
						(xy -0.22733 0.01651) (xy -0.22733 0.02667) (xy -0.2286 0.0381) (xy -0.22733 0.04953) (xy -0.22733 0.05969)
						(xy -0.22606 0.07112) (xy -0.22352 0.08128) (xy -0.22225 0.09144) (xy -0.21844 0.10287) (xy -0.2159 0.11303)
						(xy -0.21209 0.12319) (xy -0.20701 0.13335) (xy -0.2032 0.14224) (xy -0.19812 0.1524) (xy -0.17272 0.18796)
						(xy -0.1651 0.19558) (xy -0.1651 0.7366) (xy -0.16256 0.76835) (xy -0.1524 0.8001) (xy -0.13716 0.82804)
						(xy -0.11684 0.85344) (xy -0.09144 0.87376) (xy -0.0635 0.889) (xy -0.03175 0.89916) (xy 0 0.9017)
						(xy 0.03175 0.89916) (xy 0.0635 0.889) (xy 0.09144 0.87376) (xy 0.11684 0.85344) (xy 0.13716 0.82804)
						(xy 0.1524 0.8001) (xy 0.16256 0.76835) (xy 0.1651 0.7366) (xy 0.1651 0.19685) (xy 0.17272 0.18923)
						(xy 0.17907 0.18034) (xy 0.18669 0.17145) (xy 0.19177 0.16256) (xy 0.19812 0.15367) (xy 0.20828 0.13335)
						(xy 0.21971 0.10287) (xy 0.22225 0.09271) (xy 0.22479 0.08128) (xy 0.22606 0.07112) (xy 0.2286 0.05969)
						(xy 0.2286 0.01651) (xy 0.22606 0.00508) (xy 0.22479 -0.00508) (xy 0.22225 -0.01651) (xy 0.21971 -0.02667)
						(xy 0.20828 -0.05715) (xy 0.19812 -0.07747) (xy 0.19177 -0.08636) (xy 0.18669 -0.09525) (xy 0.17907 -0.10414)
						(xy 0.17272 -0.11303) (xy 0.1651 -0.12065) (xy 0.1651 -0.7366) (xy 0.16256 -0.76835) (xy 0.1524 -0.8001)
						(xy 0.13716 -0.82804) (xy 0.11684 -0.85344) (xy 0.09144 -0.87376) (xy 0.0635 -0.889) (xy 0.03175 -0.89916)
					)
					(width 0)
					(fill yes)
				)
			)
		)
		(pad "81" smd custom
			(at -5.249926 -4.100068 180)
			(size 0.1143 0.1143)
			(layers "B.Cu" "B.Mask" "B.Paste")
			(net "M_B_ECC2")
			(options
				(clearance outline)
				(anchor circle)
			)
			(primitives
				(gr_poly
					(pts
						(xy 0 -0.9017) (xy -0.03175 -0.89916) (xy -0.0635 -0.889) (xy -0.09144 -0.87376) (xy -0.11684 -0.85344)
						(xy -0.13716 -0.82804) (xy -0.1524 -0.8001) (xy -0.16256 -0.76835) (xy -0.1651 -0.7366) (xy -0.1651 -0.44958)
						(xy -0.17272 -0.44196) (xy -0.19812 -0.4064) (xy -0.2032 -0.39624) (xy -0.20701 -0.38735) (xy -0.21209 -0.37719)
						(xy -0.2159 -0.36703) (xy -0.21844 -0.35687) (xy -0.22225 -0.34544) (xy -0.22352 -0.33528) (xy -0.22606 -0.32512)
						(xy -0.22733 -0.31369) (xy -0.22733 -0.30353) (xy -0.2286 -0.2921) (xy -0.22733 -0.28067) (xy -0.22733 -0.27051)
						(xy -0.22606 -0.25908) (xy -0.22352 -0.24892) (xy -0.22225 -0.23876) (xy -0.21844 -0.22733) (xy -0.2159 -0.21717)
						(xy -0.21209 -0.20701) (xy -0.20701 -0.19685) (xy -0.2032 -0.18796) (xy -0.19812 -0.1778) (xy -0.17272 -0.14224)
						(xy -0.1651 -0.13462) (xy -0.1651 0.7366) (xy -0.16256 0.76835) (xy -0.1524 0.8001) (xy -0.13716 0.82804)
						(xy -0.11684 0.85344) (xy -0.09144 0.87376) (xy -0.0635 0.889) (xy -0.03175 0.89916) (xy 0 0.9017)
						(xy 0.03175 0.89916) (xy 0.0635 0.889) (xy 0.09144 0.87376) (xy 0.11684 0.85344) (xy 0.13716 0.82804)
						(xy 0.1524 0.8001) (xy 0.16256 0.76835) (xy 0.1651 0.7366) (xy 0.1651 -0.13462) (xy 0.17272 -0.14224)
						(xy 0.19812 -0.1778) (xy 0.2032 -0.18796) (xy 0.20701 -0.19685) (xy 0.21209 -0.20701) (xy 0.2159 -0.21717)
						(xy 0.21844 -0.22733) (xy 0.22225 -0.23876) (xy 0.22352 -0.24892) (xy 0.22606 -0.25908) (xy 0.22733 -0.27051)
						(xy 0.22733 -0.28067) (xy 0.2286 -0.2921) (xy 0.22733 -0.30353) (xy 0.22733 -0.31369) (xy 0.22606 -0.32512)
						(xy 0.22352 -0.33528) (xy 0.22225 -0.34544) (xy 0.21844 -0.35687) (xy 0.2159 -0.36703) (xy 0.21209 -0.37719)
						(xy 0.20701 -0.38735) (xy 0.2032 -0.39624) (xy 0.19812 -0.4064) (xy 0.17272 -0.44196) (xy 0.1651 -0.44958)
						(xy 0.1651 -0.7366) (xy 0.16256 -0.76835) (xy 0.1524 -0.8001) (xy 0.13716 -0.82804) (xy 0.11684 -0.85344)
						(xy 0.09144 -0.87376) (xy 0.0635 -0.889) (xy 0.03175 -0.89916)
					)
					(width 0)
					(fill yes)
				)
			)
		)
		(pad "82" smd custom
			(at -4.949952 4.100068 180)
			(size 0.1143 0.1143)
			(layers "B.Cu" "B.Mask" "B.Paste")
			(net "M_B_ECC7")
			(options
				(clearance outline)
				(anchor circle)
			)
			(primitives
				(gr_poly
					(pts
						(xy 0 -0.9017) (xy -0.03175 -0.89916) (xy -0.0635 -0.889) (xy -0.09144 -0.87376) (xy -0.11684 -0.85344)
						(xy -0.13716 -0.82804) (xy -0.1524 -0.8001) (xy -0.16256 -0.76835) (xy -0.1651 -0.7366) (xy -0.1651 0.13462)
						(xy -0.17272 0.14224) (xy -0.19812 0.1778) (xy -0.2032 0.18796) (xy -0.20701 0.19685) (xy -0.21209 0.20701)
						(xy -0.2159 0.21717) (xy -0.21844 0.22733) (xy -0.22225 0.23876) (xy -0.22352 0.24892) (xy -0.22606 0.25908)
						(xy -0.22733 0.27051) (xy -0.22733 0.28067) (xy -0.2286 0.2921) (xy -0.22733 0.30353) (xy -0.22733 0.31369)
						(xy -0.22606 0.32512) (xy -0.22352 0.33528) (xy -0.22225 0.34544) (xy -0.21844 0.35687) (xy -0.2159 0.36703)
						(xy -0.21209 0.37719) (xy -0.20701 0.38735) (xy -0.2032 0.39624) (xy -0.19812 0.4064) (xy -0.17272 0.44196)
						(xy -0.1651 0.44958) (xy -0.1651 0.7366) (xy -0.16256 0.76835) (xy -0.1524 0.8001) (xy -0.13716 0.82804)
						(xy -0.11684 0.85344) (xy -0.09144 0.87376) (xy -0.0635 0.889) (xy -0.03175 0.89916) (xy 0 0.9017)
						(xy 0.03175 0.89916) (xy 0.0635 0.889) (xy 0.09144 0.87376) (xy 0.11684 0.85344) (xy 0.13716 0.82804)
						(xy 0.1524 0.8001) (xy 0.16256 0.76835) (xy 0.1651 0.7366) (xy 0.1651 0.44958) (xy 0.17272 0.44196)
						(xy 0.19812 0.4064) (xy 0.2032 0.39624) (xy 0.20701 0.38735) (xy 0.21209 0.37719) (xy 0.2159 0.36703)
						(xy 0.21844 0.35687) (xy 0.22225 0.34544) (xy 0.22352 0.33528) (xy 0.22606 0.32512) (xy 0.22733 0.31369)
						(xy 0.22733 0.30353) (xy 0.2286 0.2921) (xy 0.22733 0.28067) (xy 0.22733 0.27051) (xy 0.22606 0.25908)
						(xy 0.22352 0.24892) (xy 0.22225 0.23876) (xy 0.21844 0.22733) (xy 0.2159 0.21717) (xy 0.21209 0.20701)
						(xy 0.20701 0.19685) (xy 0.2032 0.18796) (xy 0.19812 0.1778) (xy 0.17272 0.14224) (xy 0.1651 0.13462)
						(xy 0.1651 -0.7366) (xy 0.16256 -0.76835) (xy 0.1524 -0.8001) (xy 0.13716 -0.82804) (xy 0.11684 -0.85344)
						(xy 0.09144 -0.87376) (xy 0.0635 -0.889) (xy 0.03175 -0.89916)
					)
					(width 0)
					(fill yes)
				)
			)
		)
		(pad "83" smd custom
			(at -4.649978 -4.100068 180)
			(size 0.1143 0.1143)
			(layers "B.Cu" "B.Mask" "B.Paste")
			(net "M_B_ECC3")
			(options
				(clearance outline)
				(anchor circle)
			)
			(primitives
				(gr_poly
					(pts
						(xy 0 -0.9017) (xy -0.03175 -0.89916) (xy -0.0635 -0.889) (xy -0.09144 -0.87376) (xy -0.11684 -0.85344)
						(xy -0.13716 -0.82804) (xy -0.1524 -0.8001) (xy -0.16256 -0.76835) (xy -0.1651 -0.7366) (xy -0.1651 -0.19685)
						(xy -0.17272 -0.18923) (xy -0.17907 -0.18034) (xy -0.18669 -0.17145) (xy -0.19177 -0.16256) (xy -0.19812 -0.15367)
						(xy -0.20828 -0.13335) (xy -0.21971 -0.10287) (xy -0.22225 -0.09271) (xy -0.22479 -0.08128) (xy -0.22606 -0.07112)
						(xy -0.2286 -0.05969) (xy -0.2286 -0.01651) (xy -0.22606 -0.00508) (xy -0.22479 0.00508) (xy -0.22225 0.01651)
						(xy -0.21971 0.02667) (xy -0.20828 0.05715) (xy -0.19812 0.07747) (xy -0.19177 0.08636) (xy -0.18669 0.09525)
						(xy -0.17907 0.10414) (xy -0.17272 0.11303) (xy -0.1651 0.12065) (xy -0.1651 0.7366) (xy -0.16256 0.76835)
						(xy -0.1524 0.8001) (xy -0.13716 0.82804) (xy -0.11684 0.85344) (xy -0.09144 0.87376) (xy -0.0635 0.889)
						(xy -0.03175 0.89916) (xy 0 0.9017) (xy 0.03175 0.89916) (xy 0.0635 0.889) (xy 0.09144 0.87376)
						(xy 0.11684 0.85344) (xy 0.13716 0.82804) (xy 0.1524 0.8001) (xy 0.16256 0.76835) (xy 0.1651 0.7366)
						(xy 0.1651 0.11938) (xy 0.17272 0.11176) (xy 0.19812 0.0762) (xy 0.2032 0.06604) (xy 0.20701 0.05715)
						(xy 0.21209 0.04699) (xy 0.2159 0.03683) (xy 0.21844 0.02667) (xy 0.22225 0.01524) (xy 0.22352 0.00508)
						(xy 0.22606 -0.00508) (xy 0.22733 -0.01651) (xy 0.22733 -0.02667) (xy 0.2286 -0.0381) (xy 0.22733 -0.04953)
						(xy 0.22733 -0.05969) (xy 0.22606 -0.07112) (xy 0.22352 -0.08128) (xy 0.22225 -0.09144) (xy 0.21844 -0.10287)
						(xy 0.2159 -0.11303) (xy 0.21209 -0.12319) (xy 0.20701 -0.13335) (xy 0.2032 -0.14224) (xy 0.19812 -0.1524)
						(xy 0.17272 -0.18796) (xy 0.1651 -0.19558) (xy 0.1651 -0.7366) (xy 0.16256 -0.76835) (xy 0.1524 -0.8001)
						(xy 0.13716 -0.82804) (xy 0.11684 -0.85344) (xy 0.09144 -0.87376) (xy 0.0635 -0.889) (xy 0.03175 -0.89916)
					)
					(width 0)
					(fill yes)
				)
			)
		)
	)
)
